# SCM (Grand Teton) — schematic netlist excerpt (pin names and nets, part order shuffled) for the footprints in the layout excerpt that follows; sources: Cadence DE-HDL packaged netlist, KiCad conversion of 12092022_DA0F0TMDCD0_F0T_Management_Board_D_brd_V3_OCP.brd

R307  Q_RES  0 5% CHIP  pkg 0402LF  page 41 : A = P3V3_AUX ; B = VCCIO4
C22  Q_CAP  0.1UF 25V 10% X7R  pkg 0402  page 12 : A = P0V6_DDR_VREF_AUX ; B = GND

(kicad_pcb
	(version 20260206)
	(generator "pcbnew")
	(generator_version "10.0")
	(general
		(thickness 1.6)
		(legacy_teardrops no)
	)
	(paper "A4")
	(title_block
		(title "12092022_DA0F0TMDCD0_F0T_Management_Board_D_brd_V3_OCP.brd")
		(comment 1 "Grand Teton / footprints 917-918 of 1440")
	)
	(layers
		(0 "F.Cu" signal "TOP")
		(4 "In1.Cu" signal "GND")
		(6 "In2.Cu" signal "IN1")
		(8 "In3.Cu" signal "GND1")
		(10 "In4.Cu" signal "IN2")
		(12 "In5.Cu" signal "VCC")
		(14 "In6.Cu" signal "VCC1")
		(16 "In7.Cu" signal "IN3")
		(18 "In8.Cu" signal "GND2")
		(20 "In9.Cu" signal "IN4")
		(22 "In10.Cu" signal "GND3")
		(2 "B.Cu" signal "BOTTOM")
		(9 "F.Adhes" user "F.Adhesive")
		(11 "B.Adhes" user "B.Adhesive")
		(13 "F.Paste" user "Package Geometry/Pastemask Top")
		(15 "B.Paste" user "Package Geometry/Pastemask Bottom")
		(5 "F.SilkS" user "Ref Des/Silkscreen Top")
		(7 "B.SilkS" user "Ref Des/Silkscreen Bottom")
		(1 "F.Mask" user "Board Geometry/Soldermask Top")
		(3 "B.Mask" user "Board Geometry/Soldermask Bottom")
		(17 "Dwgs.User" user "User.Drawings")
		(19 "Cmts.User" user "User.Comments")
		(21 "Eco1.User" user "User.Eco1")
		(23 "Eco2.User" user "User.Eco2")
		(25 "Edge.Cuts" user "Board Geometry/Outline")
		(27 "Margin" user)
		(31 "F.CrtYd" user "Package Geometry/Place Bound Top")
		(29 "B.CrtYd" user "Package Geometry/Place Bound Bottom")
		(35 "F.Fab" user "Ref Des/Assembly Top")
		(33 "B.Fab" user "Ref Des/Assembly Bottom")
	)
	(footprint ""
		(layer "B.Cu")
		(at 62.103 -52.832 -90)
		(property "Reference" "C22"
			(at 0 0 90)
			(layer "B.SilkS")
			(hide yes)
			(effects
				(font
					(size 1.27 1.27)
				)
				(justify mirror)
			)
		)
		(property "Value" ""
			(at 0 0 90)
			(layer "B.Fab")
			(effects
				(font
					(size 1.27 1.27)
				)
				(justify mirror)
			)
		)
		(duplicate_pad_numbers_are_jumpers no)
		(fp_line
			(start -0.7874 0.4064)
			(end 0.7874 0.4064)
			(stroke
				(width 0.1524)
				(type default)
			)
			(layer "B.SilkS")
		)
		(fp_line
			(start 0.7874 0.4064)
			(end 0.7874 -0.4064)
			(stroke
				(width 0.1524)
				(type default)
			)
			(layer "B.SilkS")
		)
		(fp_line
			(start -0.7874 -0.4064)
			(end -0.7874 0.4064)
			(stroke
				(width 0.1524)
				(type default)
			)
			(layer "B.SilkS")
		)
		(fp_line
			(start 0.7874 -0.4064)
			(end -0.7874 -0.4064)
			(stroke
				(width 0.1524)
				(type default)
			)
			(layer "B.SilkS")
		)
		(fp_line
			(start -0.67945 0.3048)
			(end -0.120396 0.3048)
			(stroke
				(width 0.1)
				(type default)
			)
			(layer "B.Fab")
		)
		(fp_line
			(start -0.120396 0.3048)
			(end -0.120396 0.2794)
			(stroke
				(width 0.1)
				(type default)
			)
			(layer "B.Fab")
		)
		(fp_line
			(start 0.12065 0.3048)
			(end 0.67945 0.3048)
			(stroke
				(width 0.1)
				(type default)
			)
			(layer "B.Fab")
		)
		(fp_line
			(start 0.67945 0.3048)
			(end 0.67945 -0.305054)
			(stroke
				(width 0.1)
				(type default)
			)
			(layer "B.Fab")
		)
		(fp_line
			(start -0.120396 0.2794)
			(end 0.12065 0.2794)
			(stroke
				(width 0.1)
				(type default)
			)
			(layer "B.Fab")
		)
		(fp_line
			(start 0.12065 0.2794)
			(end 0.12065 0.3048)
			(stroke
				(width 0.1)
				(type default)
			)
			(layer "B.Fab")
		)
		(fp_line
			(start -0.12065 -0.2794)
			(end -0.12065 -0.3048)
			(stroke
				(width 0.1)
				(type default)
			)
			(layer "B.Fab")
		)
		(fp_line
			(start 0.12065 -0.2794)
			(end -0.12065 -0.2794)
			(stroke
				(width 0.1)
				(type default)
			)
			(layer "B.Fab")
		)
		(fp_line
			(start -0.67945 -0.3048)
			(end -0.67945 0.3048)
			(stroke
				(width 0.1)
				(type default)
			)
			(layer "B.Fab")
		)
		(fp_line
			(start -0.12065 -0.3048)
			(end -0.67945 -0.3048)
			(stroke
				(width 0.1)
				(type default)
			)
			(layer "B.Fab")
		)
		(fp_line
			(start 0.12065 -0.305054)
			(end 0.12065 -0.2794)
			(stroke
				(width 0.1)
				(type default)
			)
			(layer "B.Fab")
		)
		(fp_line
			(start 0.67945 -0.305054)
			(end 0.12065 -0.305054)
			(stroke
				(width 0.1)
				(type default)
			)
			(layer "B.Fab")
		)
		(pad "1" smd circle
			(at 0.40005 0 90)
			(size 0 0)
			(layers "B.Cu" "B.Mask" "B.Paste")
			(net "P0V6_DDR_VREF_AUX")
		)
		(pad "2" smd circle
			(at -0.40005 0 90)
			(size 0 0)
			(layers "B.Cu" "B.Mask" "B.Paste")
			(net "GND")
		)
	)
	(footprint ""
		(layer "B.Cu")
		(at 25.019 -92.456)
		(property "Reference" "R307"
			(at 0 0 0)
			(layer "B.SilkS")
			(hide yes)
			(effects
				(font
					(size 1.27 1.27)
				)
				(justify mirror)
			)
		)
		(property "Value" ""
			(at 0 0 0)
			(layer "B.Fab")
			(effects
				(font
					(size 1.27 1.27)
				)
				(justify mirror)
			)
		)
		(duplicate_pad_numbers_are_jumpers no)
		(fp_line
			(start -0.7874 -0.4064)
			(end -0.7874 0.4064)
			(stroke
				(width 0.1524)
				(type default)
			)
			(layer "B.SilkS")
		)
		(fp_line
			(start -0.7874 0.4064)
			(end 0.7874 0.4064)
			(stroke
				(width 0.1524)
				(type default)
			)
			(layer "B.SilkS")
		)
		(fp_line
			(start 0.7874 -0.4064)
			(end -0.7874 -0.4064)
			(stroke
				(width 0.1524)
				(type default)
			)
			(layer "B.SilkS")
		)
		(fp_line
			(start 0.7874 0.4064)
			(end 0.7874 -0.4064)
			(stroke
				(width 0.1524)
				(type default)
			)
			(layer "B.SilkS")
		)
		(fp_line
			(start -0.67945 -0.3048)
			(end -0.67945 0.3048)
			(stroke
				(width 0.1)
				(type default)
			)
			(layer "B.Fab")
		)
		(fp_line
			(start -0.67945 0.3048)
			(end -0.120396 0.3048)
			(stroke
				(width 0.1)
				(type default)
			)
			(layer "B.Fab")
		)
		(fp_line
			(start -0.12065 -0.3048)
			(end -0.67945 -0.3048)
			(stroke
				(width 0.1)
				(type default)
			)
			(layer "B.Fab")
		)
		(fp_line
			(start -0.12065 -0.2794)
			(end -0.12065 -0.3048)
			(stroke
				(width 0.1)
				(type default)
			)
			(layer "B.Fab")
		)
		(fp_line
			(start -0.120396 0.2794)
			(end 0.12065 0.2794)
			(stroke
				(width 0.1)
				(type default)
			)
			(layer "B.Fab")
		)
		(fp_line
			(start -0.120396 0.3048)
			(end -0.120396 0.2794)
			(stroke
				(width 0.1)
				(type default)
			)
			(layer "B.Fab")
		)
		(fp_line
			(start 0.12065 -0.305054)
			(end 0.12065 -0.2794)
			(stroke
				(width 0.1)
				(type default)
			)
			(layer "B.Fab")
		)
		(fp_line
			(start 0.12065 -0.2794)
			(end -0.12065 -0.2794)
			(stroke
				(width 0.1)
				(type default)
			)
			(layer "B.Fab")
		)
		(fp_line
			(start 0.12065 0.2794)
			(end 0.12065 0.3048)
			(stroke
				(width 0.1)
				(type default)
			)
			(layer "B.Fab")
		)
		(fp_line
			(start 0.12065 0.3048)
			(end 0.67945 0.3048)
			(stroke
				(width 0.1)
				(type default)
			)
			(layer "B.Fab")
		)
		(fp_line
			(start 0.67945 -0.305054)
			(end 0.12065 -0.305054)
			(stroke
				(width 0.1)
				(type default)
			)
			(layer "B.Fab")
		)
		(fp_line
			(start 0.67945 0.3048)
			(end 0.67945 -0.305054)
			(stroke
				(width 0.1)
				(type default)
			)
			(layer "B.Fab")
		)
		(pad "1" smd circle
			(at 0.40005 0 180)
			(size 0 0)
			(layers "B.Cu" "B.Mask" "B.Paste")
			(net "P3V3_AUX")
		)
		(pad "2" smd circle
			(at -0.40005 0 180)
			(size 0 0)
			(layers "B.Cu" "B.Mask" "B.Paste")
			(net "VCCIO4")
		)
	)
)
